(kicad_pcb
	(version 20260206)
	(generator "pcbnew")
	(generator_version "10.0")
	(general
		(thickness 1.6)
		(legacy_teardrops no)
	)
	(paper "A4")
	(title_block
		(title "Wiwynn_Tioga_Pass_MB.brd")
		(comment 1 "Tioga Pass / footprints 2522-2529 of 4770")
	)
	(layers
		(0 "F.Cu" signal "TOP")
		(4 "In1.Cu" signal "L2GND")
		(6 "In2.Cu" signal "L3")
		(8 "In3.Cu" signal "L4GND")
		(10 "In4.Cu" signal "L5")
		(12 "In5.Cu" signal "L6GND")
		(14 "In6.Cu" signal "L7VCC")
		(16 "In7.Cu" signal "L8VCC")
		(18 "In8.Cu" signal "L9GND")
		(20 "In9.Cu" signal "L10")
		(22 "In10.Cu" signal "L11GND")
		(24 "In11.Cu" signal "L12")
		(26 "In12.Cu" signal "L13GND")
		(2 "B.Cu" signal "BOTTOM")
		(9 "F.Adhes" user "F.Adhesive")
		(11 "B.Adhes" user "B.Adhesive")
		(13 "F.Paste" user "Package Geometry/Pastemask Top")
		(15 "B.Paste" user "Package Geometry/Pastemask Bottom")
		(5 "F.SilkS" user "Ref Des/Silkscreen Top")
		(7 "B.SilkS" user "Ref Des/Silkscreen Bottom")
		(1 "F.Mask" user "Board Geometry/Soldermask Top")
		(3 "B.Mask" user "Board Geometry/Soldermask Bottom")
		(17 "Dwgs.User" user "User.Drawings")
		(19 "Cmts.User" user "User.Comments")
		(21 "Eco1.User" user "User.Eco1")
		(23 "Eco2.User" user "User.Eco2")
		(25 "Edge.Cuts" user "Board Geometry/Outline")
		(27 "Margin" user)
		(31 "F.CrtYd" user "Package Geometry/Place Bound Top")
		(29 "B.CrtYd" user "Package Geometry/Place Bound Bottom")
		(35 "F.Fab" user "Ref Des/Assembly Top")
		(33 "B.Fab" user "Ref Des/Assembly Bottom")
	)
	(footprint ""
		(layer "B.Cu")
		(at 486.7402 -39.7002 180)
		(property "Reference" "C1T3"
			(at 0 0 0)
			(layer "B.SilkS")
			(hide yes)
			(effects
				(font
					(size 1.27 1.27)
				)
				(justify mirror)
			)
		)
		(property "Value" ""
			(at 0 0 0)
			(layer "B.Fab")
			(effects
				(font
					(size 1.27 1.27)
				)
				(justify mirror)
			)
		)
		(duplicate_pad_numbers_are_jumpers no)
		(fp_poly
			(pts
				(xy -0.3048 -0.1016) (xy -0.3048 0.9906) (xy 0.3048 0.9906) (xy 0.3048 -0.1016)
			)
			(stroke
				(width 0)
				(type default)
			)
			(fill no)
			(layer "B.CrtYd")
		)
		(fp_line
			(start 0.3048 0.9906)
			(end -0.3048 0.9906)
			(stroke
				(width 0.1)
				(type default)
			)
			(layer "B.Fab")
		)
		(fp_line
			(start 0.3048 -0.1016)
			(end 0.3048 0.9906)
			(stroke
				(width 0.1)
				(type default)
			)
			(layer "B.Fab")
		)
		(fp_line
			(start -0.3048 0.9906)
			(end -0.3048 -0.1016)
			(stroke
				(width 0.1)
				(type default)
			)
			(layer "B.Fab")
		)
		(fp_line
			(start -0.3048 -0.1016)
			(end 0.3048 -0.1016)
			(stroke
				(width 0.1)
				(type default)
			)
			(layer "B.Fab")
		)
		(pad "1" smd rect
			(at 0 0)
			(size 0.508 0.508)
			(layers "B.Cu" "B.Mask" "B.Paste")
			(net "P3V3_STBY")
		)
		(pad "2" smd rect
			(at 0 0.889)
			(size 0.508 0.508)
			(layers "B.Cu" "B.Mask" "B.Paste")
			(net "GND")
		)
		(zone
			(layer "B.Cu")
			(hatch none 0.5)
			(connect_pads
				(clearance 0)
			)
			(min_thickness 0.25)
			(keepout
				(tracks not_allowed)
				(vias allowed)
				(pads allowed)
				(copperpour not_allowed)
				(footprints allowed)
			)
			(placement
				(enabled no)
				(sheetname "")
			)
			(fill
				(thermal_gap 0.5)
				(thermal_bridge_width 0.5)
				(island_removal_mode 0)
			)
			(polygon
				(pts
					(xy 486.4862 -40.3352) (xy 486.9942 -40.3352) (xy 486.9942 -39.9542) (xy 486.4862 -39.9542)
				)
			)
		)
		(zone
			(layer "B.Cu")
			(hatch none 0.5)
			(connect_pads
				(clearance 0)
			)
			(min_thickness 0.25)
			(keepout
				(tracks allowed)
				(vias not_allowed)
				(pads allowed)
				(copperpour not_allowed)
				(footprints allowed)
			)
			(placement
				(enabled no)
				(sheetname "")
			)
			(fill
				(thermal_gap 0.5)
				(thermal_bridge_width 0.5)
				(island_removal_mode 0)
			)
			(polygon
				(pts
					(xy 486.4862 -39.9542) (xy 486.9942 -39.9542) (xy 486.9942 -40.3352) (xy 486.4862 -40.3352)
				)
			)
		)
	)
	(footprint ""
		(layer "B.Cu")
		(at 408.051 -6.9215 180)
		(property "Reference" "R8D38"
			(at 0 0 0)
			(layer "B.SilkS")
			(hide yes)
			(effects
				(font
					(size 1.27 1.27)
				)
				(justify mirror)
			)
		)
		(property "Value" ""
			(at 0 0 0)
			(layer "B.Fab")
			(effects
				(font
					(size 1.27 1.27)
				)
				(justify mirror)
			)
		)
		(duplicate_pad_numbers_are_jumpers no)
		(fp_poly
			(pts
				(xy 0.2794 -0.1016) (xy -0.2794 -0.1016) (xy -0.2794 0.9906) (xy 0.2794 0.9906)
			)
			(stroke
				(width 0)
				(type default)
			)
			(fill no)
			(layer "B.CrtYd")
		)
		(fp_line
			(start 0.2794 0.9906)
			(end -0.2794 0.9906)
			(stroke
				(width 0.1)
				(type default)
			)
			(layer "B.Fab")
		)
		(fp_line
			(start 0.2794 -0.1016)
			(end 0.2794 0.9906)
			(stroke
				(width 0.1)
				(type default)
			)
			(layer "B.Fab")
		)
		(fp_line
			(start -0.2794 0.9906)
			(end -0.2794 -0.1016)
			(stroke
				(width 0.1)
				(type default)
			)
			(layer "B.Fab")
		)
		(fp_line
			(start -0.2794 -0.1016)
			(end 0.2794 -0.1016)
			(stroke
				(width 0.1)
				(type default)
			)
			(layer "B.Fab")
		)
		(pad "1" smd rect
			(at 0 0)
			(size 0.508 0.508)
			(layers "B.Cu" "B.Mask" "B.Paste")
			(net "P12V")
		)
		(pad "2" smd rect
			(at 0 0.889)
			(size 0.508 0.508)
			(layers "B.Cu" "B.Mask" "B.Paste")
			(net "A_PG_P12V_MAIN")
		)
		(zone
			(layer "B.Cu")
			(hatch none 0.5)
			(connect_pads
				(clearance 0)
			)
			(min_thickness 0.25)
			(keepout
				(tracks not_allowed)
				(vias allowed)
				(pads allowed)
				(copperpour not_allowed)
				(footprints allowed)
			)
			(placement
				(enabled no)
				(sheetname "")
			)
			(fill
				(thermal_gap 0.5)
				(thermal_bridge_width 0.5)
				(island_removal_mode 0)
			)
			(polygon
				(pts
					(xy 407.797 -7.5565) (xy 408.305 -7.5565) (xy 408.305 -7.1755) (xy 407.797 -7.1755)
				)
			)
		)
		(zone
			(layer "B.Cu")
			(hatch none 0.5)
			(connect_pads
				(clearance 0)
			)
			(min_thickness 0.25)
			(keepout
				(tracks allowed)
				(vias not_allowed)
				(pads allowed)
				(copperpour not_allowed)
				(footprints allowed)
			)
			(placement
				(enabled no)
				(sheetname "")
			)
			(fill
				(thermal_gap 0.5)
				(thermal_bridge_width 0.5)
				(island_removal_mode 0)
			)
			(polygon
				(pts
					(xy 407.797 -7.1755) (xy 408.305 -7.1755) (xy 408.305 -7.5565) (xy 407.797 -7.5565)
				)
			)
		)
	)
	(footprint ""
		(layer "B.Cu")
		(at 365.76 -62.2935 180)
		(property "Reference" "R3R3"
			(at 0 0 0)
			(layer "B.SilkS")
			(hide yes)
			(effects
				(font
					(size 1.27 1.27)
				)
				(justify mirror)
			)
		)
		(property "Value" ""
			(at 0 0 0)
			(layer "B.Fab")
			(effects
				(font
					(size 1.27 1.27)
				)
				(justify mirror)
			)
		)
		(duplicate_pad_numbers_are_jumpers no)
		(fp_poly
			(pts
				(xy 0.2794 -0.1016) (xy -0.2794 -0.1016) (xy -0.2794 0.9906) (xy 0.2794 0.9906)
			)
			(stroke
				(width 0)
				(type default)
			)
			(fill no)
			(layer "B.CrtYd")
		)
		(fp_line
			(start 0.2794 0.9906)
			(end -0.2794 0.9906)
			(stroke
				(width 0.1)
				(type default)
			)
			(layer "B.Fab")
		)
		(fp_line
			(start 0.2794 -0.1016)
			(end 0.2794 0.9906)
			(stroke
				(width 0.1)
				(type default)
			)
			(layer "B.Fab")
		)
		(fp_line
			(start -0.2794 0.9906)
			(end -0.2794 -0.1016)
			(stroke
				(width 0.1)
				(type default)
			)
			(layer "B.Fab")
		)
		(fp_line
			(start -0.2794 -0.1016)
			(end 0.2794 -0.1016)
			(stroke
				(width 0.1)
				(type default)
			)
			(layer "B.Fab")
		)
		(pad "1" smd rect
			(at 0 0)
			(size 0.508 0.508)
			(layers "B.Cu" "B.Mask" "B.Paste")
			(net "PWRGD_CPUPWRGD_R1")
		)
		(pad "2" smd rect
			(at 0 0.889)
			(size 0.508 0.508)
			(layers "B.Cu" "B.Mask" "B.Paste")
			(net "PWRGD_CPUPWRGD")
		)
		(zone
			(layer "B.Cu")
			(hatch none 0.5)
			(connect_pads
				(clearance 0)
			)
			(min_thickness 0.25)
			(keepout
				(tracks not_allowed)
				(vias allowed)
				(pads allowed)
				(copperpour not_allowed)
				(footprints allowed)
			)
			(placement
				(enabled no)
				(sheetname "")
			)
			(fill
				(thermal_gap 0.5)
				(thermal_bridge_width 0.5)
				(island_removal_mode 0)
			)
			(polygon
				(pts
					(xy 365.506 -62.9285) (xy 366.014 -62.9285) (xy 366.014 -62.5475) (xy 365.506 -62.5475)
				)
			)
		)
		(zone
			(layer "B.Cu")
			(hatch none 0.5)
			(connect_pads
				(clearance 0)
			)
			(min_thickness 0.25)
			(keepout
				(tracks allowed)
				(vias not_allowed)
				(pads allowed)
				(copperpour not_allowed)
				(footprints allowed)
			)
			(placement
				(enabled no)
				(sheetname "")
			)
			(fill
				(thermal_gap 0.5)
				(thermal_bridge_width 0.5)
				(island_removal_mode 0)
			)
			(polygon
				(pts
					(xy 365.506 -62.5475) (xy 366.014 -62.5475) (xy 366.014 -62.9285) (xy 365.506 -62.9285)
				)
			)
		)
	)
	(footprint ""
		(layer "B.Cu")
		(at 401.454874 -23.114)
		(property "Reference" "C9G14"
			(at 0 0 0)
			(layer "B.SilkS")
			(hide yes)
			(effects
				(font
					(size 1.27 1.27)
				)
				(justify mirror)
			)
		)
		(property "Value" ""
			(at 0 0 0)
			(layer "B.Fab")
			(effects
				(font
					(size 1.27 1.27)
				)
				(justify mirror)
			)
		)
		(duplicate_pad_numbers_are_jumpers no)
		(fp_poly
			(pts
				(xy -0.3048 -0.1016) (xy -0.3048 0.9906) (xy 0.3048 0.9906) (xy 0.3048 -0.1016)
			)
			(stroke
				(width 0)
				(type default)
			)
			(fill no)
			(layer "B.CrtYd")
		)
		(fp_line
			(start -0.3048 -0.1016)
			(end 0.3048 -0.1016)
			(stroke
				(width 0.1)
				(type default)
			)
			(layer "B.Fab")
		)
		(fp_line
			(start -0.3048 0.9906)
			(end -0.3048 -0.1016)
			(stroke
				(width 0.1)
				(type default)
			)
			(layer "B.Fab")
		)
		(fp_line
			(start 0.3048 -0.1016)
			(end 0.3048 0.9906)
			(stroke
				(width 0.1)
				(type default)
			)
			(layer "B.Fab")
		)
		(fp_line
			(start 0.3048 0.9906)
			(end -0.3048 0.9906)
			(stroke
				(width 0.1)
				(type default)
			)
			(layer "B.Fab")
		)
		(pad "1" smd rect
			(at 0 0 180)
			(size 0.508 0.508)
			(layers "B.Cu" "B.Mask" "B.Paste")
			(net "A_P3V3_SCALED")
		)
		(pad "2" smd rect
			(at 0 0.889 180)
			(size 0.508 0.508)
			(layers "B.Cu" "B.Mask" "B.Paste")
			(net "GND")
		)
		(zone
			(layer "B.Cu")
			(hatch none 0.5)
			(connect_pads
				(clearance 0)
			)
			(min_thickness 0.25)
			(keepout
				(tracks allowed)
				(vias not_allowed)
				(pads allowed)
				(copperpour not_allowed)
				(footprints allowed)
			)
			(placement
				(enabled no)
				(sheetname "")
			)
			(fill
				(thermal_gap 0.5)
				(thermal_bridge_width 0.5)
				(island_removal_mode 0)
			)
			(polygon
				(pts
					(xy 401.708874 -22.86) (xy 401.200874 -22.86) (xy 401.200874 -22.479) (xy 401.708874 -22.479)
				)
			)
		)
		(zone
			(layer "B.Cu")
			(hatch none 0.5)
			(connect_pads
				(clearance 0)
			)
			(min_thickness 0.25)
			(keepout
				(tracks not_allowed)
				(vias allowed)
				(pads allowed)
				(copperpour not_allowed)
				(footprints allowed)
			)
			(placement
				(enabled no)
				(sheetname "")
			)
			(fill
				(thermal_gap 0.5)
				(thermal_bridge_width 0.5)
				(island_removal_mode 0)
			)
			(polygon
				(pts
					(xy 401.708874 -22.479) (xy 401.200874 -22.479) (xy 401.200874 -22.86) (xy 401.708874 -22.86)
				)
			)
		)
	)
	(footprint ""
		(layer "B.Cu")
		(at 354.289614 -125.532642 -90)
		(property "Reference" "R760"
			(at 0.8382 -0.67818 270)
			(unlocked yes)
			(layer "B.SilkS")
			(effects
				(font
					(size 0.4064 0.254)
					(thickness 0.1524)
				)
				(justify left mirror)
			)
		)
		(property "Value" ""
			(at 0 0 90)
			(layer "B.Fab")
			(effects
				(font
					(size 1.27 1.27)
				)
				(justify mirror)
			)
		)
		(duplicate_pad_numbers_are_jumpers no)
		(fp_poly
			(pts
				(xy 0.2794 -0.1016) (xy -0.2794 -0.1016) (xy -0.2794 0.9906) (xy 0.2794 0.9906)
			)
			(stroke
				(width 0)
				(type default)
			)
			(fill no)
			(layer "B.CrtYd")
		)
		(fp_line
			(start -0.2794 0.9906)
			(end -0.2794 -0.1016)
			(stroke
				(width 0.1)
				(type default)
			)
			(layer "B.Fab")
		)
		(fp_line
			(start 0.2794 0.9906)
			(end -0.2794 0.9906)
			(stroke
				(width 0.1)
				(type default)
			)
			(layer "B.Fab")
		)
		(fp_line
			(start -0.2794 -0.1016)
			(end 0.2794 -0.1016)
			(stroke
				(width 0.1)
				(type default)
			)
			(layer "B.Fab")
		)
		(fp_line
			(start 0.2794 -0.1016)
			(end 0.2794 0.9906)
			(stroke
				(width 0.1)
				(type default)
			)
			(layer "B.Fab")
		)
		(pad "1" smd rect
			(at 0 0 90)
			(size 0.508 0.508)
			(layers "B.Cu" "B.Mask" "B.Paste")
			(net "P3E_CPU0_PE1_PCH_RXN<15>")
		)
		(pad "2" smd rect
			(at 0 0.889 90)
			(size 0.508 0.508)
			(layers "B.Cu" "B.Mask" "B.Paste")
			(net "P3E_CPU0_PE1_PCH_CON_RXN<15>")
		)
		(zone
			(layer "B.Cu")
			(hatch none 0.5)
			(connect_pads
				(clearance 0)
			)
			(min_thickness 0.25)
			(keepout
				(tracks not_allowed)
				(vias allowed)
				(pads allowed)
				(copperpour not_allowed)
				(footprints allowed)
			)
			(placement
				(enabled no)
				(sheetname "")
			)
			(fill
				(thermal_gap 0.5)
				(thermal_bridge_width 0.5)
				(island_removal_mode 0)
			)
			(polygon
				(pts
					(xy 353.654614 -125.278642) (xy 353.654614 -125.786642) (xy 354.035614 -125.786642) (xy 354.035614 -125.278642)
				)
			)
		)
		(zone
			(layer "B.Cu")
			(hatch none 0.5)
			(connect_pads
				(clearance 0)
			)
			(min_thickness 0.25)
			(keepout
				(tracks allowed)
				(vias not_allowed)
				(pads allowed)
				(copperpour not_allowed)
				(footprints allowed)
			)
			(placement
				(enabled no)
				(sheetname "")
			)
			(fill
				(thermal_gap 0.5)
				(thermal_bridge_width 0.5)
				(island_removal_mode 0)
			)
			(polygon
				(pts
					(xy 354.035614 -125.278642) (xy 354.035614 -125.786642) (xy 353.654614 -125.786642) (xy 353.654614 -125.278642)
				)
			)
		)
	)
	(footprint ""
		(layer "B.Cu")
		(at 361.826556 -121.392442 -90)
		(property "Reference" "R779"
			(at 0.8382 -0.67818 270)
			(unlocked yes)
			(layer "B.SilkS")
			(effects
				(font
					(size 0.4064 0.254)
					(thickness 0.1524)
				)
				(justify left mirror)
			)
		)
		(property "Value" ""
			(at 0 0 90)
			(layer "B.Fab")
			(effects
				(font
					(size 1.27 1.27)
				)
				(justify mirror)
			)
		)
		(duplicate_pad_numbers_are_jumpers no)
		(fp_poly
			(pts
				(xy 0.2794 -0.1016) (xy -0.2794 -0.1016) (xy -0.2794 0.9906) (xy 0.2794 0.9906)
			)
			(stroke
				(width 0)
				(type default)
			)
			(fill no)
			(layer "B.CrtYd")
		)
		(fp_line
			(start -0.2794 0.9906)
			(end -0.2794 -0.1016)
			(stroke
				(width 0.1)
				(type default)
			)
			(layer "B.Fab")
		)
		(fp_line
			(start 0.2794 0.9906)
			(end -0.2794 0.9906)
			(stroke
				(width 0.1)
				(type default)
			)
			(layer "B.Fab")
		)
		(fp_line
			(start -0.2794 -0.1016)
			(end 0.2794 -0.1016)
			(stroke
				(width 0.1)
				(type default)
			)
			(layer "B.Fab")
		)
		(fp_line
			(start 0.2794 -0.1016)
			(end 0.2794 0.9906)
			(stroke
				(width 0.1)
				(type default)
			)
			(layer "B.Fab")
		)
		(pad "1" smd rect
			(at 0 0 90)
			(size 0.508 0.508)
			(layers "B.Cu" "B.Mask" "B.Paste")
			(net "P3E_CPU0_PE1_PCH_RXP<11>")
		)
		(pad "2" smd rect
			(at 0 0.889 90)
			(size 0.508 0.508)
			(layers "B.Cu" "B.Mask" "B.Paste")
			(net "P3E_CPU0_PE1_PCH_CON_RXP<11>")
		)
		(zone
			(layer "B.Cu")
			(hatch none 0.5)
			(connect_pads
				(clearance 0)
			)
			(min_thickness 0.25)
			(keepout
				(tracks not_allowed)
				(vias allowed)
				(pads allowed)
				(copperpour not_allowed)
				(footprints allowed)
			)
			(placement
				(enabled no)
				(sheetname "")
			)
			(fill
				(thermal_gap 0.5)
				(thermal_bridge_width 0.5)
				(island_removal_mode 0)
			)
			(polygon
				(pts
					(xy 361.191556 -121.138442) (xy 361.191556 -121.646442) (xy 361.572556 -121.646442) (xy 361.572556 -121.138442)
				)
			)
		)
		(zone
			(layer "B.Cu")
			(hatch none 0.5)
			(connect_pads
				(clearance 0)
			)
			(min_thickness 0.25)
			(keepout
				(tracks allowed)
				(vias not_allowed)
				(pads allowed)
				(copperpour not_allowed)
				(footprints allowed)
			)
			(placement
				(enabled no)
				(sheetname "")
			)
			(fill
				(thermal_gap 0.5)
				(thermal_bridge_width 0.5)
				(island_removal_mode 0)
			)
			(polygon
				(pts
					(xy 361.572556 -121.138442) (xy 361.572556 -121.646442) (xy 361.191556 -121.646442) (xy 361.191556 -121.138442)
				)
			)
		)
	)
	(footprint ""
		(layer "B.Cu")
		(at 308.768496 -33.874202)
		(property "Reference" ""
			(at 0 0 0)
			(layer "B.SilkS")
			(hide yes)
			(effects
				(font
					(size 1.27 1.27)
				)
				(justify mirror)
			)
		)
		(property "Value" ""
			(at 0 0 0)
			(layer "B.Fab")
			(effects
				(font
					(size 1.27 1.27)
				)
				(justify mirror)
			)
		)
		(duplicate_pad_numbers_are_jumpers no)
		(fp_poly
			(pts
				(arc
					(start 2.032 0)
					(mid -2.032 0)
					(end 2.032 0)
				)
			)
			(stroke
				(width 0)
				(type default)
			)
			(fill no)
			(layer "B.CrtYd")
		)
		(pad "1" smd circle
			(at 0 0 180)
			(size 1.016 1.016)
			(layers "B.Cu" "B.Mask" "B.Paste")
			(net "Net_398")
		)
		(zone
			(layers "F.Cu" "B.Cu" "In1.Cu" "In2.Cu" "In3.Cu" "In4.Cu" "In5.Cu" "In6.Cu"
				"In7.Cu" "In8.Cu" "In9.Cu" "In10.Cu" "In11.Cu" "In12.Cu"
			)
			(hatch none 0.5)
			(connect_pads
				(clearance 0)
			)
			(min_thickness 0.25)
			(keepout
				(tracks allowed)
				(vias not_allowed)
				(pads allowed)
				(copperpour not_allowed)
				(footprints allowed)
			)
			(placement
				(enabled no)
				(sheetname "")
			)
			(fill
				(thermal_gap 0.5)
				(thermal_bridge_width 0.5)
				(island_removal_mode 0)
			)
			(polygon
				(pts
					(arc
						(start 310.292496 -33.874202)
						(mid 307.244496 -33.874202)
						(end 310.292496 -33.874202)
					)
				)
			)
		)
		(zone
			(layer "B.Cu")
			(hatch none 0.5)
			(connect_pads
				(clearance 0)
			)
			(min_thickness 0.25)
			(keepout
				(tracks not_allowed)
				(vias allowed)
				(pads allowed)
				(copperpour not_allowed)
				(footprints allowed)
			)
			(placement
				(enabled no)
				(sheetname "")
			)
			(fill
				(thermal_gap 0.5)
				(thermal_bridge_width 0.5)
				(island_removal_mode 0)
			)
			(polygon
				(pts
					(arc
						(start 310.292496 -33.874202)
						(mid 307.244496 -33.874202)
						(end 310.292496 -33.874202)
					)
				)
			)
		)
	)
	(footprint ""
		(layer "B.Cu")
		(at 183.261 -13.589 180)
		(property "Reference" "C6U4"
			(at 0 0 0)
			(layer "B.SilkS")
			(hide yes)
			(effects
				(font
					(size 1.27 1.27)
				)
				(justify mirror)
			)
		)
		(property "Value" ""
			(at 0 0 0)
			(layer "B.Fab")
			(effects
				(font
					(size 1.27 1.27)
				)
				(justify mirror)
			)
		)
		(duplicate_pad_numbers_are_jumpers no)
		(fp_poly
			(pts
				(xy 0.7239 -0.2159) (xy -0.7239 -0.2159) (xy -0.7239 1.9939) (xy 0.7239 1.9939)
			)
			(stroke
				(width 0)
				(type default)
			)
			(fill no)
			(layer "B.CrtYd")
		)
		(fp_line
			(start 0.7239 1.9939)
			(end -0.7239 1.9939)
			(stroke
				(width 0.1)
				(type default)
			)
			(layer "B.Fab")
		)
		(fp_line
			(start 0.7239 -0.2159)
			(end 0.7239 1.9939)
			(stroke
				(width 0.1)
				(type default)
			)
			(layer "B.Fab")
		)
		(fp_line
			(start -0.7239 1.9939)
			(end -0.7239 -0.2159)
			(stroke
				(width 0.1)
				(type default)
			)
			(layer "B.Fab")
		)
		(fp_line
			(start -0.7239 -0.2159)
			(end 0.7239 -0.2159)
			(stroke
				(width 0.1)
				(type default)
			)
			(layer "B.Fab")
		)
		(pad "1" smd rect
			(at 0 0)
			(size 1.27 1.016)
			(layers "B.Cu" "B.Mask" "B.Paste")
			(net "VR_FET_SW_P12V_STBY_PVPP_GHJ")
		)
		(pad "2" smd rect
			(at 0 1.778)
			(size 1.27 1.016)
			(layers "B.Cu" "B.Mask" "B.Paste")
			(net "GND")
		)
		(zone
			(layer "B.Cu")
			(hatch none 0.5)
			(connect_pads
				(clearance 0)
			)
			(min_thickness 0.25)
			(keepout
				(tracks not_allowed)
				(vias allowed)
				(pads allowed)
				(copperpour not_allowed)
				(footprints allowed)
			)
			(placement
				(enabled no)
				(sheetname "")
			)
			(fill
				(thermal_gap 0.5)
				(thermal_bridge_width 0.5)
				(island_removal_mode 0)
			)
			(polygon
				(pts
					(xy 182.626 -14.097) (xy 183.896 -14.097) (xy 183.896 -14.859) (xy 182.626 -14.859)
				)
			)
		)
	)
)
